(kicad_pcb
	(version 20260206)
	(generator "pcbnew")
	(generator_version "10.0")
	(general
		(thickness 1.6)
		(legacy_teardrops no)
	)
	(paper "A4")
	(title_block
		(title "Wiwynn_Tioga_Pass_MB.brd")
		(comment 1 "Tioga Pass / footprints 2784-2790 of 4770")
	)
	(layers
		(0 "F.Cu" signal "TOP")
		(4 "In1.Cu" signal "L2GND")
		(6 "In2.Cu" signal "L3")
		(8 "In3.Cu" signal "L4GND")
		(10 "In4.Cu" signal "L5")
		(12 "In5.Cu" signal "L6GND")
		(14 "In6.Cu" signal "L7VCC")
		(16 "In7.Cu" signal "L8VCC")
		(18 "In8.Cu" signal "L9GND")
		(20 "In9.Cu" signal "L10")
		(22 "In10.Cu" signal "L11GND")
		(24 "In11.Cu" signal "L12")
		(26 "In12.Cu" signal "L13GND")
		(2 "B.Cu" signal "BOTTOM")
		(9 "F.Adhes" user "F.Adhesive")
		(11 "B.Adhes" user "B.Adhesive")
		(13 "F.Paste" user "Package Geometry/Pastemask Top")
		(15 "B.Paste" user "Package Geometry/Pastemask Bottom")
		(5 "F.SilkS" user "Ref Des/Silkscreen Top")
		(7 "B.SilkS" user "Ref Des/Silkscreen Bottom")
		(1 "F.Mask" user "Board Geometry/Soldermask Top")
		(3 "B.Mask" user "Board Geometry/Soldermask Bottom")
		(17 "Dwgs.User" user "User.Drawings")
		(19 "Cmts.User" user "User.Comments")
		(21 "Eco1.User" user "User.Eco1")
		(23 "Eco2.User" user "User.Eco2")
		(25 "Edge.Cuts" user "Board Geometry/Outline")
		(27 "Margin" user)
		(31 "F.CrtYd" user "Package Geometry/Place Bound Top")
		(29 "B.CrtYd" user "Package Geometry/Place Bound Bottom")
		(35 "F.Fab" user "Ref Des/Assembly Top")
		(33 "B.Fab" user "Ref Des/Assembly Bottom")
	)
	(footprint ""
		(layer "B.Cu")
		(at 197.848728 -76.157582 90)
		(property "Reference" "C6P17"
			(at 0 0 90)
			(layer "B.SilkS")
			(hide yes)
			(effects
				(font
					(size 1.27 1.27)
				)
				(justify mirror)
			)
		)
		(property "Value" ""
			(at 0 0 90)
			(layer "B.Fab")
			(effects
				(font
					(size 1.27 1.27)
				)
				(justify mirror)
			)
		)
		(duplicate_pad_numbers_are_jumpers no)
		(fp_rect
			(start -0.7239 -0.2159)
			(end 0.7239 1.9939)
			(stroke
				(width 0)
				(type default)
			)
			(fill no)
			(layer "B.CrtYd")
		)
		(fp_line
			(start 0.7239 -0.2159)
			(end 0.7239 1.9939)
			(stroke
				(width 0.1)
				(type default)
			)
			(layer "B.Fab")
		)
		(fp_line
			(start -0.7239 -0.2159)
			(end 0.7239 -0.2159)
			(stroke
				(width 0.1)
				(type default)
			)
			(layer "B.Fab")
		)
		(fp_line
			(start 0.7239 1.9939)
			(end -0.7239 1.9939)
			(stroke
				(width 0.1)
				(type default)
			)
			(layer "B.Fab")
		)
		(fp_line
			(start -0.7239 1.9939)
			(end -0.7239 -0.2159)
			(stroke
				(width 0.1)
				(type default)
			)
			(layer "B.Fab")
		)
		(pad "1" smd rect
			(at 0 0 270)
			(size 1.27 1.016)
			(layers "B.Cu" "B.Mask" "B.Paste")
			(net "VR_FET_SW_P12V_STBY_PVCCIN_CPU0")
		)
		(pad "2" smd rect
			(at 0 1.778 270)
			(size 1.27 1.016)
			(layers "B.Cu" "B.Mask" "B.Paste")
			(net "GND")
		)
		(zone
			(layer "B.Cu")
			(hatch none 0.5)
			(connect_pads
				(clearance 0)
			)
			(min_thickness 0.25)
			(keepout
				(tracks not_allowed)
				(vias allowed)
				(pads allowed)
				(copperpour not_allowed)
				(footprints allowed)
			)
			(placement
				(enabled no)
				(sheetname "")
			)
			(fill
				(thermal_gap 0.5)
				(thermal_bridge_width 0.5)
				(island_removal_mode 0)
			)
			(polygon
				(pts
					(xy 198.356728 -75.522582) (xy 199.118728 -75.522582) (xy 199.118728 -76.792582) (xy 198.356728 -76.792582)
				)
			)
		)
	)
	(footprint ""
		(layer "B.Cu")
		(at 439.02884 -21.29282 90)
		(property "Reference" "R3W5"
			(at 0.8382 -0.67818 90)
			(unlocked yes)
			(layer "B.SilkS")
			(effects
				(font
					(size 0.4064 0.254)
					(thickness 0.1524)
				)
				(justify left mirror)
			)
		)
		(property "Value" ""
			(at 0 0 90)
			(layer "B.Fab")
			(effects
				(font
					(size 1.27 1.27)
				)
				(justify mirror)
			)
		)
		(duplicate_pad_numbers_are_jumpers no)
		(fp_poly
			(pts
				(xy 0.2794 -0.1016) (xy -0.2794 -0.1016) (xy -0.2794 0.9906) (xy 0.2794 0.9906)
			)
			(stroke
				(width 0)
				(type default)
			)
			(fill no)
			(layer "B.CrtYd")
		)
		(fp_line
			(start 0.2794 -0.1016)
			(end 0.2794 0.9906)
			(stroke
				(width 0.1)
				(type default)
			)
			(layer "B.Fab")
		)
		(fp_line
			(start -0.2794 -0.1016)
			(end 0.2794 -0.1016)
			(stroke
				(width 0.1)
				(type default)
			)
			(layer "B.Fab")
		)
		(fp_line
			(start 0.2794 0.9906)
			(end -0.2794 0.9906)
			(stroke
				(width 0.1)
				(type default)
			)
			(layer "B.Fab")
		)
		(fp_line
			(start -0.2794 0.9906)
			(end -0.2794 -0.1016)
			(stroke
				(width 0.1)
				(type default)
			)
			(layer "B.Fab")
		)
		(pad "1" smd rect
			(at 0 0 270)
			(size 0.508 0.508)
			(layers "B.Cu" "B.Mask" "B.Paste")
			(net "P3V3_STBY")
		)
		(pad "2" smd rect
			(at 0 0.889 270)
			(size 0.508 0.508)
			(layers "B.Cu" "B.Mask" "B.Paste")
			(net "FM_TPM_PRES_RST")
		)
		(zone
			(layer "B.Cu")
			(hatch none 0.5)
			(connect_pads
				(clearance 0)
			)
			(min_thickness 0.25)
			(keepout
				(tracks allowed)
				(vias not_allowed)
				(pads allowed)
				(copperpour not_allowed)
				(footprints allowed)
			)
			(placement
				(enabled no)
				(sheetname "")
			)
			(fill
				(thermal_gap 0.5)
				(thermal_bridge_width 0.5)
				(island_removal_mode 0)
			)
			(polygon
				(pts
					(xy 439.28284 -21.54682) (xy 439.28284 -21.03882) (xy 439.66384 -21.03882) (xy 439.66384 -21.54682)
				)
			)
		)
		(zone
			(layer "B.Cu")
			(hatch none 0.5)
			(connect_pads
				(clearance 0)
			)
			(min_thickness 0.25)
			(keepout
				(tracks not_allowed)
				(vias allowed)
				(pads allowed)
				(copperpour not_allowed)
				(footprints allowed)
			)
			(placement
				(enabled no)
				(sheetname "")
			)
			(fill
				(thermal_gap 0.5)
				(thermal_bridge_width 0.5)
				(island_removal_mode 0)
			)
			(polygon
				(pts
					(xy 439.66384 -21.54682) (xy 439.66384 -21.03882) (xy 439.28284 -21.03882) (xy 439.28284 -21.54682)
				)
			)
		)
	)
	(footprint ""
		(layer "B.Cu")
		(at 362.1024 -133.0198 180)
		(property "Reference" "R3M5"
			(at 0 0 0)
			(layer "B.SilkS")
			(hide yes)
			(effects
				(font
					(size 1.27 1.27)
				)
				(justify mirror)
			)
		)
		(property "Value" ""
			(at 0 0 0)
			(layer "B.Fab")
			(effects
				(font
					(size 1.27 1.27)
				)
				(justify mirror)
			)
		)
		(duplicate_pad_numbers_are_jumpers no)
		(fp_poly
			(pts
				(xy 0.2794 -0.1016) (xy -0.2794 -0.1016) (xy -0.2794 0.9906) (xy 0.2794 0.9906)
			)
			(stroke
				(width 0)
				(type default)
			)
			(fill no)
			(layer "B.CrtYd")
		)
		(fp_line
			(start 0.2794 0.9906)
			(end -0.2794 0.9906)
			(stroke
				(width 0.1)
				(type default)
			)
			(layer "B.Fab")
		)
		(fp_line
			(start 0.2794 -0.1016)
			(end 0.2794 0.9906)
			(stroke
				(width 0.1)
				(type default)
			)
			(layer "B.Fab")
		)
		(fp_line
			(start -0.2794 0.9906)
			(end -0.2794 -0.1016)
			(stroke
				(width 0.1)
				(type default)
			)
			(layer "B.Fab")
		)
		(fp_line
			(start -0.2794 -0.1016)
			(end 0.2794 -0.1016)
			(stroke
				(width 0.1)
				(type default)
			)
			(layer "B.Fab")
		)
		(pad "1" smd rect
			(at 0 0)
			(size 0.508 0.508)
			(layers "B.Cu" "B.Mask" "B.Paste")
			(net "P3V3_STBY")
		)
		(pad "2" smd rect
			(at 0 0.889)
			(size 0.508 0.508)
			(layers "B.Cu" "B.Mask" "B.Paste")
			(net "VR_PVDDQ_DEF_VREN")
		)
		(zone
			(layer "B.Cu")
			(hatch none 0.5)
			(connect_pads
				(clearance 0)
			)
			(min_thickness 0.25)
			(keepout
				(tracks not_allowed)
				(vias allowed)
				(pads allowed)
				(copperpour not_allowed)
				(footprints allowed)
			)
			(placement
				(enabled no)
				(sheetname "")
			)
			(fill
				(thermal_gap 0.5)
				(thermal_bridge_width 0.5)
				(island_removal_mode 0)
			)
			(polygon
				(pts
					(xy 361.8484 -133.6548) (xy 362.3564 -133.6548) (xy 362.3564 -133.2738) (xy 361.8484 -133.2738)
				)
			)
		)
		(zone
			(layer "B.Cu")
			(hatch none 0.5)
			(connect_pads
				(clearance 0)
			)
			(min_thickness 0.25)
			(keepout
				(tracks allowed)
				(vias not_allowed)
				(pads allowed)
				(copperpour not_allowed)
				(footprints allowed)
			)
			(placement
				(enabled no)
				(sheetname "")
			)
			(fill
				(thermal_gap 0.5)
				(thermal_bridge_width 0.5)
				(island_removal_mode 0)
			)
			(polygon
				(pts
					(xy 361.8484 -133.2738) (xy 362.3564 -133.2738) (xy 362.3564 -133.6548) (xy 361.8484 -133.6548)
				)
			)
		)
	)
	(footprint ""
		(layer "B.Cu")
		(at 385.33705 -107.85475 90)
		(property "Reference" "C3N17"
			(at 0 0 90)
			(layer "B.SilkS")
			(hide yes)
			(effects
				(font
					(size 1.27 1.27)
				)
				(justify mirror)
			)
		)
		(property "Value" ""
			(at 0 0 90)
			(layer "B.Fab")
			(effects
				(font
					(size 1.27 1.27)
				)
				(justify mirror)
			)
		)
		(duplicate_pad_numbers_are_jumpers no)
		(fp_rect
			(start 0.2794 0.9144)
			(end -0.2794 -0.1143)
			(stroke
				(width 0)
				(type default)
			)
			(fill no)
			(layer "B.CrtYd")
		)
		(fp_line
			(start 0.2794 -0.1143)
			(end -0.2794 -0.1143)
			(stroke
				(width 0.1)
				(type default)
			)
			(layer "B.Fab")
		)
		(fp_line
			(start -0.2794 -0.1143)
			(end -0.2794 0.9144)
			(stroke
				(width 0.1)
				(type default)
			)
			(layer "B.Fab")
		)
		(fp_line
			(start 0.2794 0.9144)
			(end 0.2794 -0.1143)
			(stroke
				(width 0.1)
				(type default)
			)
			(layer "B.Fab")
		)
		(fp_line
			(start -0.2794 0.9144)
			(end 0.2794 0.9144)
			(stroke
				(width 0.1)
				(type default)
			)
			(layer "B.Fab")
		)
		(pad "1" smd custom
			(at 0 0)
			(size 0.10414 0.10414)
			(layers "B.Cu" "B.Mask" "B.Paste")
			(net "PVNN_PCH_STBY")
			(options
				(clearance outline)
				(anchor circle)
			)
			(primitives
				(gr_poly
					(pts
						(xy -0.20828 -0.08636) (xy -0.20828 0.08636) (xy -0.08636 0.20828) (xy 0.086614 0.20828) (xy 0.20828 0.086614)
						(xy 0.20828 -0.08636) (xy 0.08636 -0.20828) (xy -0.08636 -0.20828)
					)
					(width 0)
					(fill yes)
				)
			)
		)
		(pad "2" smd custom
			(at 0 0.8001)
			(size 0.10414 0.10414)
			(layers "B.Cu" "B.Mask" "B.Paste")
			(net "GND")
			(options
				(clearance outline)
				(anchor circle)
			)
			(primitives
				(gr_poly
					(pts
						(xy -0.20828 -0.08636) (xy -0.20828 0.08636) (xy -0.08636 0.20828) (xy 0.086614 0.20828) (xy 0.20828 0.086614)
						(xy 0.20828 -0.08636) (xy 0.08636 -0.20828) (xy -0.08636 -0.20828)
					)
					(width 0)
					(fill yes)
				)
			)
		)
		(zone
			(layer "B.Cu")
			(hatch none 0.5)
			(connect_pads
				(clearance 0)
			)
			(min_thickness 0.25)
			(keepout
				(tracks allowed)
				(vias not_allowed)
				(pads allowed)
				(copperpour not_allowed)
				(footprints allowed)
			)
			(placement
				(enabled no)
				(sheetname "")
			)
			(fill
				(thermal_gap 0.5)
				(thermal_bridge_width 0.5)
				(island_removal_mode 0)
			)
			(polygon
				(pts
					(xy 385.5466 -107.94238) (xy 385.9276 -107.94238) (xy 385.9276 -107.76712) (xy 385.5466 -107.766866)
				)
			)
		)
		(zone
			(layer "B.Cu")
			(hatch none 0.5)
			(connect_pads
				(clearance 0)
			)
			(min_thickness 0.25)
			(keepout
				(tracks not_allowed)
				(vias allowed)
				(pads allowed)
				(copperpour not_allowed)
				(footprints allowed)
			)
			(placement
				(enabled no)
				(sheetname "")
			)
			(fill
				(thermal_gap 0.5)
				(thermal_bridge_width 0.5)
				(island_removal_mode 0)
			)
			(polygon
				(pts
					(xy 385.5466 -107.94238) (xy 385.9276 -107.94238) (xy 385.9276 -107.76712) (xy 385.5466 -107.766866)
				)
			)
		)
	)
	(footprint ""
		(layer "B.Cu")
		(at 500.253 -148.1582 -90)
		(property "Reference" "U6W6"
			(at 0.14986 2.621788 270)
			(unlocked yes)
			(layer "B.SilkS")
			(effects
				(font
					(size 1.27 0.964946)
					(thickness 0.000001)
				)
				(justify left mirror)
			)
		)
		(property "Value" ""
			(at 0 0 90)
			(layer "B.Fab")
			(effects
				(font
					(size 1.27 1.27)
				)
				(justify mirror)
			)
		)
		(duplicate_pad_numbers_are_jumpers no)
		(fp_circle
			(center 0.4699 -0.8382)
			(end 0.4699 -0.9652)
			(stroke
				(width 0.254)
				(type default)
			)
			(fill no)
			(layer "B.SilkS")
		)
		(fp_poly
			(pts
				(xy -0.21463 -0.450088) (xy -1.56337 -0.450088) (xy -1.56337 1.75006) (xy -0.21463 1.75006)
			)
			(stroke
				(width 0)
				(type default)
			)
			(fill no)
			(layer "B.CrtYd")
		)
		(fp_line
			(start -1.56337 1.75006)
			(end -0.21463 1.75006)
			(stroke
				(width 0.1)
				(type default)
			)
			(layer "B.Fab")
		)
		(fp_line
			(start -0.21463 1.75006)
			(end -0.21463 -0.450088)
			(stroke
				(width 0.1)
				(type default)
			)
			(layer "B.Fab")
		)
		(fp_line
			(start -1.56337 -0.450088)
			(end -1.56337 1.75006)
			(stroke
				(width 0.1)
				(type default)
			)
			(layer "B.Fab")
		)
		(fp_line
			(start -0.21463 -0.450088)
			(end -1.56337 -0.450088)
			(stroke
				(width 0.1)
				(type default)
			)
			(layer "B.Fab")
		)
		(fp_circle
			(center 0.4699 -0.8382)
			(end 0.4699 -0.9652)
			(stroke
				(width 0.254)
				(type default)
			)
			(fill no)
			(layer "B.Fab")
		)
		(pad "1" smd rect
			(at 0 0 90)
			(size 1.016 0.381)
			(layers "B.Cu" "B.Mask" "B.Paste")
			(net "SPA_MID_DBG1_TX_EN")
		)
		(pad "2" smd rect
			(at 0 0.649986 90)
			(size 1.016 0.381)
			(layers "B.Cu" "B.Mask" "B.Paste")
			(net "SPA_MID_DBG_TX")
		)
		(pad "3" smd rect
			(at 0 1.299972 90)
			(size 1.016 0.381)
			(layers "B.Cu" "B.Mask" "B.Paste")
			(net "GND")
		)
		(pad "4" smd rect
			(at -1.778 1.299972 90)
			(size 1.016 0.381)
			(layers "B.Cu" "B.Mask" "B.Paste")
			(net "SPA_MID_DBG1_TX_R")
		)
		(pad "5" smd rect
			(at -1.778 0 90)
			(size 1.016 0.381)
			(layers "B.Cu" "B.Mask" "B.Paste")
			(net "P3V3_STBY")
		)
	)
	(footprint ""
		(layer "B.Cu")
		(at 404.5585 -97.917 -90)
		(property "Reference" "R2N10"
			(at 0 0 90)
			(layer "B.SilkS")
			(hide yes)
			(effects
				(font
					(size 1.27 1.27)
				)
				(justify mirror)
			)
		)
		(property "Value" ""
			(at 0 0 90)
			(layer "B.Fab")
			(effects
				(font
					(size 1.27 1.27)
				)
				(justify mirror)
			)
		)
		(duplicate_pad_numbers_are_jumpers no)
		(fp_poly
			(pts
				(xy 0.2794 -0.1016) (xy -0.2794 -0.1016) (xy -0.2794 0.9906) (xy 0.2794 0.9906)
			)
			(stroke
				(width 0)
				(type default)
			)
			(fill no)
			(layer "B.CrtYd")
		)
		(fp_line
			(start -0.2794 0.9906)
			(end -0.2794 -0.1016)
			(stroke
				(width 0.1)
				(type default)
			)
			(layer "B.Fab")
		)
		(fp_line
			(start 0.2794 0.9906)
			(end -0.2794 0.9906)
			(stroke
				(width 0.1)
				(type default)
			)
			(layer "B.Fab")
		)
		(fp_line
			(start -0.2794 -0.1016)
			(end 0.2794 -0.1016)
			(stroke
				(width 0.1)
				(type default)
			)
			(layer "B.Fab")
		)
		(fp_line
			(start 0.2794 -0.1016)
			(end 0.2794 0.9906)
			(stroke
				(width 0.1)
				(type default)
			)
			(layer "B.Fab")
		)
		(pad "1" smd rect
			(at 0 0 90)
			(size 0.508 0.508)
			(layers "B.Cu" "B.Mask" "B.Paste")
			(net "P3V3_STBY")
		)
		(pad "2" smd rect
			(at 0 0.889 90)
			(size 0.508 0.508)
			(layers "B.Cu" "B.Mask" "B.Paste")
			(net "FM_PCH_BMC_THERMTRIP_EXI_STRAP_")
		)
		(zone
			(layer "B.Cu")
			(hatch none 0.5)
			(connect_pads
				(clearance 0)
			)
			(min_thickness 0.25)
			(keepout
				(tracks not_allowed)
				(vias allowed)
				(pads allowed)
				(copperpour not_allowed)
				(footprints allowed)
			)
			(placement
				(enabled no)
				(sheetname "")
			)
			(fill
				(thermal_gap 0.5)
				(thermal_bridge_width 0.5)
				(island_removal_mode 0)
			)
			(polygon
				(pts
					(xy 403.9235 -97.663) (xy 403.9235 -98.171) (xy 404.3045 -98.171) (xy 404.3045 -97.663)
				)
			)
		)
		(zone
			(layer "B.Cu")
			(hatch none 0.5)
			(connect_pads
				(clearance 0)
			)
			(min_thickness 0.25)
			(keepout
				(tracks allowed)
				(vias not_allowed)
				(pads allowed)
				(copperpour not_allowed)
				(footprints allowed)
			)
			(placement
				(enabled no)
				(sheetname "")
			)
			(fill
				(thermal_gap 0.5)
				(thermal_bridge_width 0.5)
				(island_removal_mode 0)
			)
			(polygon
				(pts
					(xy 404.3045 -97.663) (xy 404.3045 -98.171) (xy 403.9235 -98.171) (xy 403.9235 -97.663)
				)
			)
		)
	)
	(footprint ""
		(layer "B.Cu")
		(at 392.692128 -88.314784 90)
		(property "Reference" "R2W3"
			(at 0.8382 -0.67818 90)
			(unlocked yes)
			(layer "B.SilkS")
			(effects
				(font
					(size 0.4064 0.254)
					(thickness 0.1524)
				)
				(justify left mirror)
			)
		)
		(property "Value" ""
			(at 0 0 90)
			(layer "B.Fab")
			(effects
				(font
					(size 1.27 1.27)
				)
				(justify mirror)
			)
		)
		(duplicate_pad_numbers_are_jumpers no)
		(fp_poly
			(pts
				(xy 0.2794 -0.1016) (xy -0.2794 -0.1016) (xy -0.2794 0.9906) (xy 0.2794 0.9906)
			)
			(stroke
				(width 0)
				(type default)
			)
			(fill no)
			(layer "B.CrtYd")
		)
		(fp_line
			(start 0.2794 -0.1016)
			(end 0.2794 0.9906)
			(stroke
				(width 0.1)
				(type default)
			)
			(layer "B.Fab")
		)
		(fp_line
			(start -0.2794 -0.1016)
			(end 0.2794 -0.1016)
			(stroke
				(width 0.1)
				(type default)
			)
			(layer "B.Fab")
		)
		(fp_line
			(start 0.2794 0.9906)
			(end -0.2794 0.9906)
			(stroke
				(width 0.1)
				(type default)
			)
			(layer "B.Fab")
		)
		(fp_line
			(start -0.2794 0.9906)
			(end -0.2794 -0.1016)
			(stroke
				(width 0.1)
				(type default)
			)
			(layer "B.Fab")
		)
		(pad "1" smd rect
			(at 0 0 270)
			(size 0.508 0.508)
			(layers "B.Cu" "B.Mask" "B.Paste")
			(net "FM_PMBUS_ALERT_BUF_EN_R_N")
		)
		(pad "2" smd rect
			(at 0 0.889 270)
			(size 0.508 0.508)
			(layers "B.Cu" "B.Mask" "B.Paste")
			(net "FM_PMBUS_ALERT_BUF_EN_N")
		)
		(zone
			(layer "B.Cu")
			(hatch none 0.5)
			(connect_pads
				(clearance 0)
			)
			(min_thickness 0.25)
			(keepout
				(tracks allowed)
				(vias not_allowed)
				(pads allowed)
				(copperpour not_allowed)
				(footprints allowed)
			)
			(placement
				(enabled no)
				(sheetname "")
			)
			(fill
				(thermal_gap 0.5)
				(thermal_bridge_width 0.5)
				(island_removal_mode 0)
			)
			(polygon
				(pts
					(xy 392.946128 -88.568784) (xy 392.946128 -88.060784) (xy 393.327128 -88.060784) (xy 393.327128 -88.568784)
				)
			)
		)
		(zone
			(layer "B.Cu")
			(hatch none 0.5)
			(connect_pads
				(clearance 0)
			)
			(min_thickness 0.25)
			(keepout
				(tracks not_allowed)
				(vias allowed)
				(pads allowed)
				(copperpour not_allowed)
				(footprints allowed)
			)
			(placement
				(enabled no)
				(sheetname "")
			)
			(fill
				(thermal_gap 0.5)
				(thermal_bridge_width 0.5)
				(island_removal_mode 0)
			)
			(polygon
				(pts
					(xy 393.327128 -88.568784) (xy 393.327128 -88.060784) (xy 392.946128 -88.060784) (xy 392.946128 -88.568784)
				)
			)
		)
	)
)
